FILE_TYPE = CONNECTIVITY;
{Allegro Design Entry HDL 16.6-p007 (v16-6-112F) 10/10/2012}
"PAGE_NUMBER" = 161;
0"NC";
1"GND\g";
2"P3V3_STBY\g";
3"P12V_FAN\g";
4"P12V_FAN\g";
5"GND\g";
6"P3V3_STBY\g";
7"GND\g";
8"P3V3_STBY\g";
9"GND\g";
10"GND\g";
11"GND\g";
12"GND\g";
13"P3V3_STBY\g";
14"P5V_STBY\g";
15"P3V3_STBY\g";
16"P5V_STBY\g";
17"GND\g";
18"P3V3_STBY\g";
19"GND\g";
20"FAN_PWM_OUT_SYS1_R";
21"FAN_PWM_OUT_SYS0_R";
22"FAN_TACH2";
23"FAN_TACH2_CPU1_D1";
24"FAN_TACH0_CPU0_D2";
25"FAN_TACH0_CPU0_D1";
26"FM_ENABLE_FAN_POWER";
27"FAN_PWM_OUT_SYS0_R";
28"FAN_TACH0";
29"FAN_PWM_OUT_SYS1_R";
30"FAN_PWM_OUT_SYS1_BUF";
31"FAN_PWM_OUT_SYS1";
32"FAN_PWM_OUT_SYS0_BUF";
33"FM_CTNR_PS_ON";
34"FM_DISABLE_FAN_N";
35"FAN_PWM_OUT_SYS0";
36"FAN_TACH2_CPU1_D2";
%"RES"
"1","(-5600,1100)","0","mstr_discrete","I102";
;
CDS_SEC"1"
LOCATION"R2U44"
PART_NUMBER"G21796-271"
VALUE"221"
TOLERANCE"1.0%"
PACK_TYPE"0402"
MATERIAL"CHIP"
WATTAGE"1/16W"
BOM_COST"SM_THERM"
ROOM"CPU_FANS"
SEC_TYPE"0402"
SEC"1"
CDS_LIB"mstr_discrete"
CDS_LOCATION"R2U44";
"B"
$PN"2"29;
"A"
$PN"1"30;
%"GND"
"1","(-6200,475)","2","mstr_symbols","I104";
;
HDL_POWER"GND"
ROOM"PLD"
SIZE"1B"
VOLTAGE"0.0V"
BODY_TYPE"PLUMBING"
CDS_LIB"mstr_symbols";
"A\NAC"1;
%"P3V3_STBY"
"1","(-6200,850)","0","mstr_symbols","I105";
;
SIZE"1B"
BODY_TYPE"PLUMBING"
VOLTAGE"3.3V"
HDL_POWER"P3V3_STBY"
CDS_LIB"mstr_symbols";
"G\NAC"2;
%"P12V_FAN"
"1","(-1375,2575)","0","mstr_symbols","I108";
;
CDS_LIB"mstr_symbols"
HDL_POWER"P12V_FAN"
VOLTAGE"12.0V"
BODY_TYPE"PLUMBING";
"G\NAC"3;
%"P12V_FAN"
"1","(-1500,4725)","0","mstr_symbols","I110";
;
BODY_TYPE"PLUMBING"
VOLTAGE"12.0V"
HDL_POWER"P12V_FAN"
CDS_LIB"mstr_symbols";
"G\NAC"4;
%"GND"
"1","(-1200,1900)","5","mstr_symbols","I111";
;
BODY_TYPE"PLUMBING"
SIZE"1B"
CDS_LIB"mstr_symbols"
VOLTAGE"0.0V"
HDL_POWER"GND";
"A\NAC"5;
%"CAP_A"
"1","(-5775,2150)","0","dev_discrete","I113";
;
LOCATION"C1E22"
VALUE"0.1UF"
VOLTAGE"16V"
PACK_TYPE"0402V"
PART_NUMBER"A36096-030"
MATERIAL"X7R"
TOLERANCE"10%"
CDS_LIB"dev_discrete"
CDS_LOCATION"C1E22"
CDS_SEC"1"
ROOM"CPUFANS"
SEC"1"
SEC_TYPE"0402V"
BOM_COST"SM_THERM";
"B"
$PN"2"7;
"A"
$PN"1"6;
%"P3V3_STBY"
"1","(-5775,2350)","0","mstr_symbols","I117";
;
HDL_POWER"P3V3_STBY"
SIZE"1B"
CDS_LIB"mstr_symbols"
VOLTAGE"3.3V"
BODY_TYPE"PLUMBING";
"G\NAC"6;
%"GND"
"1","(-5775,1950)","0","mstr_symbols","I118";
;
VOLTAGE"0.0V"
CDS_LIB"mstr_symbols"
SIZE"1B"
BODY_TYPE"PLUMBING"
HDL_POWER"GND";
"A\NAC"7;
%"P3V3_STBY"
"1","(-5950,3025)","0","mstr_symbols","I119";
;
HDL_POWER"P3V3_STBY"
BODY_TYPE"PLUMBING"
SIZE"1B"
CDS_LIB"mstr_symbols"
VOLTAGE"3.3V";
"G\NAC"8;
%"RES"
"2","(-5950,2800)","0","mstr_discrete","I120";
;
CDS_SEC"1"
PACK_TYPE"0402"
TOLERANCE"1%"
VALUE"10.0K"
LOCATION"R1E11"
WATTAGE"1/16W"
MATERIAL"EMPTY"
PART_NUMBER"G21796-016"
CDS_LIB"mstr_discrete"
CDS_LOCATION"R1E11"
ROOM"CPU_FANS"
SEC"1"
SEC_TYPE"0402"
BOM_COST"SM_THERM";
"A"
$PN"1"8;
"B"
$PN"2"26;
%"TTL1G08"
"1","(-6250,2575)","0","mstr_ttl","I121";
;
CDS_SEC"1"
VALUE"NC7SZ08"
MATERIAL"IC"
PACK_TYPE"SOTLF"
LOCATION"U1E2"
PART_NUMBER"D10321-001"
POWER_GROUP"VCC=P3V3_STBY;GND=GND;"
CDS_LOCATION"U1E2"
CDS_LIB"mstr_ttl"
ROOM"CPU_FANS"
SEC_TYPE"SOTLF"
SEC"1"
BOM_COST"SM_THERM";
"Y <SIZE-1..0>"
$PN"4"26;
"B <SIZE-1..0>"
$PN"2"34;
"A <SIZE-1..0>"
$PN"1"33;
%"GND"
"1","(-1100,3975)","5","mstr_symbols","I122";
;
HDL_POWER"GND"
CDS_LIB"mstr_symbols"
SIZE"1B"
BODY_TYPE"PLUMBING"
VOLTAGE"0.0V";
"A\NAC"9;
%"GND"
"1","(-1125,4075)","0","mstr_symbols","I13";
;
BODY_TYPE"PLUMBING"
VOLTAGE"0.0V"
SIZE"1B"
CDS_LIB"mstr_symbols"
HDL_POWER"GND";
"A\NAC"10;
%"LOTES-CON4-S1-GP"
"1","(-600,3875)","0","w_hdl","I139";
;
VALUE"LOTES-CON4-S1-GP"
LOCATION"J1F2"
CDS_SEC"1"
CDS_LMAN_SYM_OUTLINE"-75,150,75,-150"
CDS_LIB"w_hdl"
PART_NUMBER"021.60521.0104"
SEC_TYPE"CONN-G7"
SEC"1"
PACK_TYPE"CONN-G7"
CDS_LOCATION"J1F2";
"NP1"
$PN"NP1"0;
"4"
$PN"4"21;
"3"
$PN"3"25;
"2"
$PN"2"4;
"1"
$PN"1"9;
%"LOTES-CON4-S1-GP"
"1","(-650,1800)","0","w_hdl","I140";
;
VALUE"LOTES-CON4-S1-GP"
LOCATION"J10W1"
CDS_SEC"1"
CDS_LMAN_SYM_OUTLINE"-75,150,75,-150"
CDS_LIB"w_hdl"
PART_NUMBER"021.60521.0104"
SEC_TYPE"CONN-G7"
SEC"1"
PACK_TYPE"CONN-G7"
CDS_LOCATION"J10W1";
"NP1"
$PN"NP1"0;
"4"
$PN"4"20;
"3"
$PN"3"23;
"2"
$PN"2"3;
"1"
$PN"1"5;
%"CAP_A"
"1","(-1000,2275)","0","dev_discrete","I26";
;
PACK_TYPE"0402V"
LOCATION"C9M5"
VALUE"0.1UF"
VOLTAGE"16V"
PART_NUMBER"A36096-030"
MATERIAL"X7R"
TOLERANCE"10%"
CDS_LOCATION"C9M5"
BOM_COST"SM_THERM"
CDS_SEC"1"
SEC_TYPE"0402V"
SEC"1"
ROOM"CPU_FANS"
CDS_LIB"dev_discrete";
"B"
$PN"2"11;
"A"
$PN"1"3;
%"CAP"
"1","(-1300,2275)","0","mstr_discrete","I27";
;
CDS_SEC"1"
PART_NUMBER"C95333-007"
VALUE"10UF"
LOCATION"C9M4"
VOLTAGE"16V"
TOLERANCE"10%"
MATERIAL"X6S"
PACK_TYPE"0805"
ROOM"CPU_FANS"
BOM_COST"SM_THERM"
SEC_TYPE"0805"
SEC"1"
CDS_LOCATION"C9M4"
CDS_LIB"mstr_discrete";
"A"
$PN"1"3;
"B"
$PN"2"11;
%"CAP"
"1","(-1400,4350)","0","mstr_discrete","I3";
;
CDS_SEC"1"
TOLERANCE"10%"
VALUE"10UF"
LOCATION"C1E21"
VOLTAGE"16V"
PACK_TYPE"0805"
MATERIAL"X6S"
PART_NUMBER"C95333-007"
CDS_LIB"mstr_discrete"
ROOM"CPU_FANS"
CDS_LOCATION"C1E21"
SEC"1"
BOM_COST"SM_THERM"
SEC_TYPE"0805";
"A"
$PN"1"4;
"B"
$PN"2"10;
%"GND"
"1","(-1300,1950)","0","mstr_symbols","I30";
;
HDL_POWER"GND"
SIZE"1B"
VOLTAGE"0.0V"
CDS_LIB"mstr_symbols"
BODY_TYPE"PLUMBING";
"A\NAC"11;
%"CAP_A"
"1","(-1125,4325)","0","dev_discrete","I4";
;
PART_NUMBER"A36096-030"
LOCATION"C1E20"
VALUE"0.1UF"
VOLTAGE"16V"
TOLERANCE"10%"
MATERIAL"X7R"
PACK_TYPE"0402V"
CDS_LIB"dev_discrete"
SEC_TYPE"0402V"
ROOM"CPU_FANS"
CDS_LOCATION"C1E20"
SEC"1"
BOM_COST"SM_THERM"
CDS_SEC"1";
"B"
$PN"2"10;
"A"
$PN"1"4;
%"DIODE"
"1","(-1675,3825)","0","mstr_discrete","I42";
;
CDS_SEC"1"
VALUE"SDMK0340L"
LOCATION"CR1F1"
PART_NUMBER"H71799-001"
MATERIAL"IC"
PACK_TYPE"SM"
CDS_LIB"mstr_discrete"
CDS_LOCATION"CR1F1"
ROOM"CPU_FANS"
SEC"1"
SEC_TYPE"SM"
BOM_COST"SM_THERM";
"C"
$PN"1"25;
"A"
$PN"2"24;
%"RES"
"1","(-2525,3825)","0","mstr_discrete","I43";
;
CDS_SEC"1"
PACK_TYPE"0402"
LOCATION"R1F2"
WATTAGE"1/16W"
VALUE"100.0"
MATERIAL"CHIP"
TOLERANCE"1%"
PART_NUMBER"G21796-017"
SEC_TYPE"0402"
SEC"1"
CDS_LOCATION"R1F2"
NO_XNET_CONNECTION"1"
ROOM"CPU_FANS"
CDS_LIB"mstr_discrete"
BOM_COST"SM_THERM";
"B"
$PN"2"24;
"A"
$PN"1"28;
%"RES"
"2","(-2900,4025)","0","mstr_discrete","I45";
;
CDS_SEC"1"
VALUE"4.75K"
LOCATION"R1F1"
WATTAGE"1/16W"
PACK_TYPE"0402"
MATERIAL"CHIP"
PART_NUMBER"G21796-072"
TOLERANCE"1%"
CDS_LIB"mstr_discrete"
CDS_LOCATION"R1F1"
ROOM"CPU_FANS"
SEC"1"
SEC_TYPE"0402"
BOM_COST"SM_THERM";
"A"
$PN"1"13;
"B"
$PN"2"28;
%"CAP_A"
"1","(-2775,3625)","2","dev_discrete","I46";
;
PART_NUMBER"A36096-045"
MATERIAL"X7R"
PACK_TYPE"0402V"
TOLERANCE"10%"
LOCATION"C1F9"
VOLTAGE"25V"
VALUE"0.01UF"
CDS_SEC"1"
CDS_LOCATION"C1F9"
BOM_COST"SM_THERM"
SEC_TYPE"0402V"
SEC"1"
ROOM"CPU_FANS"
CDS_LIB"dev_discrete";
"B"
$PN"2"12;
"A"
$PN"1"28;
%"GND"
"1","(-2775,3375)","0","mstr_symbols","I47";
;
VOLTAGE"0.0V"
BODY_TYPE"PLUMBING"
SIZE"1B"
HDL_POWER"GND"
CDS_LIB"mstr_symbols";
"A\NAC"12;
%"P3V3_STBY"
"1","(-2900,4250)","0","mstr_symbols","I48";
;
HDL_POWER"P3V3_STBY"
BODY_TYPE"PLUMBING"
VOLTAGE"3.3V"
CDS_LIB"mstr_symbols"
SIZE"1B";
"G\NAC"13;
%"DIODE"
"4","(-1950,3325)","0","mstr_discrete","I50";
;
CDS_SEC"1"
VALUE"SDMK0340L"
MATERIAL"EMPTY"
LOCATION"CR1E1"
PACK_TYPE"SM"
PART_NUMBER"H71799-001"
CDS_LIB"mstr_discrete"
ROOM"CPU_FANS"
CDS_LOCATION"CR1E1"
SEC"1"
SEC_TYPE"SM"
BOM_COST"SM_THERM";
"A"
$PN"2"21;
"C"
$PN"1"14;
%"RES"
"2","(-2175,3400)","2","mstr_discrete","I51";
;
CDS_SEC"1"
WATTAGE"1/16W"
MATERIAL"CHIP"
LOCATION"R1E12"
VALUE"4.75K"
TOLERANCE"1%"
PART_NUMBER"G21796-072"
PACK_TYPE"0402"
CDS_LOCATION"R1E12"
CDS_LIB"mstr_discrete"
SEC_TYPE"0402"
BOM_COST"SM_THERM"
SEC"1"
ROOM"CPU_FANS";
"A"
$PN"1"14;
"B"
$PN"2"21;
%"P5V_STBY"
"1","(-1950,3625)","0","mstr_symbols","I52";
;
HDL_POWER"P5V_STBY"
BODY_TYPE"PLUMBING"
VOLTAGE"5.0V"
SIZE"1B"
CDS_LIB"mstr_symbols";
"G\NAC"14;
%"P3V3_STBY"
"1","(-3050,2175)","0","mstr_symbols","I61";
;
SIZE"1B"
CDS_LIB"mstr_symbols"
VOLTAGE"3.3V"
BODY_TYPE"PLUMBING"
HDL_POWER"P3V3_STBY";
"G\NAC"15;
%"DIODE"
"1","(-1825,1750)","0","mstr_discrete","I62";
;
CDS_SEC"1"
VALUE"SDMK0340L"
PACK_TYPE"SM"
LOCATION"CR1B2"
PART_NUMBER"H71799-001"
MATERIAL"IC"
BOM_COST"SM_THERM"
SEC_TYPE"SM"
SEC"1"
ROOM"CPU_FANS"
CDS_LOCATION"CR1B2"
CDS_LIB"mstr_discrete";
"C"
$PN"1"23;
"A"
$PN"2"36;
%"P5V_STBY"
"1","(-2100,1550)","0","mstr_symbols","I63";
;
SIZE"1B"
CDS_LIB"mstr_symbols"
VOLTAGE"5.0V"
BODY_TYPE"PLUMBING"
HDL_POWER"P5V_STBY";
"G\NAC"16;
%"DIODE"
"4","(-2100,1250)","0","mstr_discrete","I64";
;
CDS_SEC"1"
VALUE"SDMK0340L"
MATERIAL"EMPTY"
PART_NUMBER"H71799-001"
LOCATION"CR1B1"
PACK_TYPE"SM"
BOM_COST"SM_THERM"
SEC_TYPE"SM"
SEC"1"
CDS_LOCATION"CR1B1"
ROOM"CPU_FANS"
CDS_LIB"mstr_discrete";
"A"
$PN"2"20;
"C"
$PN"1"16;
%"RES"
"2","(-2325,1300)","2","mstr_discrete","I65";
;
CDS_SEC"1"
PACK_TYPE"0402"
LOCATION"R7F33"
MATERIAL"CHIP"
WATTAGE"1/16W"
TOLERANCE"1%"
VALUE"4.75K"
PART_NUMBER"G21796-072"
BOM_COST"SM_THERM"
SEC_TYPE"0402"
SEC"1"
ROOM"CPU_FANS"
CDS_LOCATION"R7F33"
CDS_LIB"mstr_discrete";
"A"
$PN"1"16;
"B"
$PN"2"20;
%"RES"
"1","(-2675,1750)","0","mstr_discrete","I67";
;
CDS_SEC"1"
WATTAGE"1/16W"
VALUE"100.0"
PACK_TYPE"0402"
MATERIAL"CHIP"
TOLERANCE"1%"
LOCATION"R1B22"
PART_NUMBER"G21796-017"
BOM_COST"SM_THERM"
CDS_LOCATION"R1B22"
SEC"1"
SEC_TYPE"0402"
NO_XNET_CONNECTION"1"
ROOM"CPU_FANS"
CDS_LIB"mstr_discrete";
"B"
$PN"2"36;
"A"
$PN"1"22;
%"CAP_A"
"1","(-2925,1550)","2","dev_discrete","I68";
;
PART_NUMBER"A36096-045"
VALUE"0.01UF"
LOCATION"C1B15"
MATERIAL"X7R"
PACK_TYPE"0402V"
TOLERANCE"10%"
VOLTAGE"25V"
CDS_LOCATION"C1B15"
SEC_TYPE"0402V"
CDS_LIB"dev_discrete"
ROOM"CPU_FANS"
SEC"1"
CDS_SEC"1"
BOM_COST"SM_THERM";
"B"
$PN"2"17;
"A"
$PN"1"22;
%"GND"
"1","(-2925,1300)","0","mstr_symbols","I69";
;
HDL_POWER"GND"
CDS_LIB"mstr_symbols"
SIZE"1B"
VOLTAGE"0.0V"
BODY_TYPE"PLUMBING";
"A\NAC"17;
%"RES"
"2","(-3050,1950)","0","mstr_discrete","I70";
;
CDS_SEC"1"
PART_NUMBER"G21796-072"
VALUE"4.75K"
TOLERANCE"1%"
MATERIAL"CHIP"
PACK_TYPE"0402"
LOCATION"R1B21"
WATTAGE"1/16W"
BOM_COST"SM_THERM"
SEC_TYPE"0402"
SEC"1"
ROOM"CPU_FANS"
CDS_LOCATION"R1B21"
CDS_LIB"mstr_discrete";
"A"
$PN"1"15;
"B"
$PN"2"22;
%"TTL1G07_A"
"1","(-6350,3850)","0","mstr_ttl","I88";
;
CDS_SEC"1"
VALUE"74LVC1G07"
LOCATION"U8G2"
MATERIAL"IC"
PART_NUMBER"C88419-001"
POWER_GROUP"VCC=P3V3_STBY;GND=GND"
CDS_LOCATION"U8G2"
CDS_LIB"mstr_ttl"
ROOM"CPU_FANS"
SEC"1"
SEC_TYPE"SOP"
BOM_COST"SM_THERM"
PACK_TYPE"SOP";
"Y"
$PN"4"32;
"A"
$PN"2"35;
%"CAP_A"
"1","(-6300,4450)","0","dev_discrete","I90";
;
VOLTAGE"16V"
PACK_TYPE"0402V"
LOCATION"C2U27"
VALUE"0.1UF"
TOLERANCE"10%"
MATERIAL"X7R"
PART_NUMBER"A36096-030"
CDS_LIB"dev_discrete"
CDS_LOCATION"C2U27"
CDS_SEC"1"
SEC"1"
SEC_TYPE"0402V"
BOM_COST"SM_THERM"
ROOM"CPU_FANS";
"B"
$PN"2"19;
"A"
$PN"1"18;
%"TTL1G07_A"
"1","(-6425,1100)","0","mstr_ttl","I92";
;
CDS_SEC"1"
PART_NUMBER"C88419-001"
MATERIAL"IC"
VALUE"74LVC1G07"
LOCATION"U8G3"
POWER_GROUP"VCC=P3V3_STBY;GND=GND"
BOM_COST"SM_THERM"
ROOM"CPU_FANS"
PACK_TYPE"SOP"
SEC"1"
SEC_TYPE"SOP"
CDS_LOCATION"U8G3"
CDS_LIB"mstr_ttl";
"Y"
$PN"4"30;
"A"
$PN"2"31;
%"CAP_A"
"1","(-6200,675)","0","dev_discrete","I93";
;
VALUE"0.1UF"
LOCATION"C2U28"
PART_NUMBER"A36096-030"
TOLERANCE"10%"
PACK_TYPE"0402V"
VOLTAGE"16V"
MATERIAL"X7R"
BOM_COST"SM_THERM"
ROOM"CPU_FANS"
SEC_TYPE"0402V"
SEC"1"
CDS_SEC"1"
CDS_LOCATION"C2U28"
CDS_LIB"dev_discrete";
"B"
$PN"2"1;
"A"
$PN"1"2;
%"P3V3_STBY"
"1","(-6300,4650)","0","mstr_symbols","I96";
;
HDL_POWER"P3V3_STBY"
BODY_TYPE"PLUMBING"
VOLTAGE"3.3V"
SIZE"1B"
CDS_LIB"mstr_symbols";
"G\NAC"18;
%"GND"
"1","(-6300,4250)","0","mstr_symbols","I97";
;
VOLTAGE"0.0V"
CDS_LIB"mstr_symbols"
BODY_TYPE"PLUMBING"
SIZE"1B"
HDL_POWER"GND";
"A\NAC"19;
%"RES"
"1","(-5450,3850)","0","mstr_discrete","I99";
;
CDS_SEC"1"
VALUE"221"
WATTAGE"1/16W"
PART_NUMBER"G21796-271"
LOCATION"R2U42"
TOLERANCE"1.0%"
MATERIAL"CHIP"
PACK_TYPE"0402"
CDS_LOCATION"R2U42"
SEC"1"
CDS_LIB"mstr_discrete"
SEC_TYPE"0402"
ROOM"CPU_FANS"
BOM_COST"SM_THERM";
"B"
$PN"2"27;
"A"
$PN"1"32;
END.
